(kicad_pcb
	(version 20260206)
	(generator "pcbnew")
	(generator_version "10.0")
	(general
		(thickness 1.6)
		(legacy_teardrops no)
	)
	(paper "A4")
	(title_block
		(title "9054_F0T_PDB_BD_GPU_F_V04_1213_1550_OCP.brd")
		(comment 1 "Grand Teton / footprints 453-457 of 608")
	)
	(layers
		(0 "F.Cu" signal "TOP")
		(4 "In1.Cu" signal "GND")
		(6 "In2.Cu" signal "IN1")
		(8 "In3.Cu" signal "GND1")
		(10 "In4.Cu" signal "VCC")
		(12 "In5.Cu" signal "VCC1")
		(14 "In6.Cu" signal "GND2")
		(16 "In7.Cu" signal "IN2")
		(18 "In8.Cu" signal "GND3")
		(2 "B.Cu" signal "BOTTOM")
		(9 "F.Adhes" user "F.Adhesive")
		(11 "B.Adhes" user "B.Adhesive")
		(13 "F.Paste" user "Package Geometry/Pastemask Top")
		(15 "B.Paste" user "Package Geometry/Pastemask Bottom")
		(5 "F.SilkS" user "Ref Des/Silkscreen Top")
		(7 "B.SilkS" user "Ref Des/Silkscreen Bottom")
		(1 "F.Mask" user "Board Geometry/Soldermask Top")
		(3 "B.Mask" user "Board Geometry/Soldermask Bottom")
		(17 "Dwgs.User" user "User.Drawings")
		(19 "Cmts.User" user "User.Comments")
		(21 "Eco1.User" user "User.Eco1")
		(23 "Eco2.User" user "User.Eco2")
		(25 "Edge.Cuts" user "Board Geometry/Outline")
		(27 "Margin" user)
		(31 "F.CrtYd" user "Package Geometry/Place Bound Top")
		(29 "B.CrtYd" user "Package Geometry/Place Bound Bottom")
		(35 "F.Fab" user "Ref Des/Assembly Top")
		(33 "B.Fab" user "Ref Des/Assembly Bottom")
	)
	(footprint ""
		(layer "B.Cu")
		(at 154.097736 -76.835 180)
		(property "Reference" "PC600"
			(at 0 0 0)
			(layer "B.SilkS")
			(hide yes)
			(effects
				(font
					(size 1.27 1.27)
				)
				(justify mirror)
			)
		)
		(property "Value" ""
			(at 0 0 0)
			(layer "B.Fab")
			(effects
				(font
					(size 1.27 1.27)
				)
				(justify mirror)
			)
		)
		(duplicate_pad_numbers_are_jumpers no)
		(fp_line
			(start 0.7874 0.4064)
			(end 0.7874 -0.4064)
			(stroke
				(width 0.1524)
				(type default)
			)
			(layer "B.SilkS")
		)
		(fp_line
			(start 0.7874 -0.4064)
			(end -0.7874 -0.4064)
			(stroke
				(width 0.1524)
				(type default)
			)
			(layer "B.SilkS")
		)
		(fp_line
			(start -0.7874 0.4064)
			(end 0.7874 0.4064)
			(stroke
				(width 0.1524)
				(type default)
			)
			(layer "B.SilkS")
		)
		(fp_line
			(start -0.7874 -0.4064)
			(end -0.7874 0.4064)
			(stroke
				(width 0.1524)
				(type default)
			)
			(layer "B.SilkS")
		)
		(fp_line
			(start 0.67945 0.3048)
			(end 0.67945 -0.305054)
			(stroke
				(width 0.1)
				(type default)
			)
			(layer "B.Fab")
		)
		(fp_line
			(start 0.67945 -0.305054)
			(end 0.12065 -0.305054)
			(stroke
				(width 0.1)
				(type default)
			)
			(layer "B.Fab")
		)
		(fp_line
			(start 0.12065 0.3048)
			(end 0.67945 0.3048)
			(stroke
				(width 0.1)
				(type default)
			)
			(layer "B.Fab")
		)
		(fp_line
			(start 0.12065 0.2794)
			(end 0.12065 0.3048)
			(stroke
				(width 0.1)
				(type default)
			)
			(layer "B.Fab")
		)
		(fp_line
			(start 0.12065 -0.2794)
			(end -0.12065 -0.2794)
			(stroke
				(width 0.1)
				(type default)
			)
			(layer "B.Fab")
		)
		(fp_line
			(start 0.12065 -0.305054)
			(end 0.12065 -0.2794)
			(stroke
				(width 0.1)
				(type default)
			)
			(layer "B.Fab")
		)
		(fp_line
			(start -0.120396 0.3048)
			(end -0.120396 0.2794)
			(stroke
				(width 0.1)
				(type default)
			)
			(layer "B.Fab")
		)
		(fp_line
			(start -0.120396 0.2794)
			(end 0.12065 0.2794)
			(stroke
				(width 0.1)
				(type default)
			)
			(layer "B.Fab")
		)
		(fp_line
			(start -0.12065 -0.2794)
			(end -0.12065 -0.3048)
			(stroke
				(width 0.1)
				(type default)
			)
			(layer "B.Fab")
		)
		(fp_line
			(start -0.12065 -0.3048)
			(end -0.67945 -0.3048)
			(stroke
				(width 0.1)
				(type default)
			)
			(layer "B.Fab")
		)
		(fp_line
			(start -0.67945 0.3048)
			(end -0.120396 0.3048)
			(stroke
				(width 0.1)
				(type default)
			)
			(layer "B.Fab")
		)
		(fp_line
			(start -0.67945 -0.3048)
			(end -0.67945 0.3048)
			(stroke
				(width 0.1)
				(type default)
			)
			(layer "B.Fab")
		)
		(pad "1" smd circle
			(at 0.40005 0)
			(size 0 0)
			(layers "B.Cu" "B.Mask" "B.Paste")
			(net "GND1_FIELD_SIGNAL")
		)
		(pad "2" smd circle
			(at -0.40005 0)
			(size 0 0)
			(layers "B.Cu" "B.Mask" "B.Paste")
			(net "P52V_HS2_DVCC")
		)
	)
	(footprint ""
		(layer "B.Cu")
		(at 260.6294 -51.689 180)
		(property "Reference" "C69"
			(at 0 0 0)
			(layer "B.SilkS")
			(hide yes)
			(effects
				(font
					(size 1.27 1.27)
				)
				(justify mirror)
			)
		)
		(property "Value" ""
			(at 0 0 0)
			(layer "B.Fab")
			(effects
				(font
					(size 1.27 1.27)
				)
				(justify mirror)
			)
		)
		(duplicate_pad_numbers_are_jumpers no)
		(fp_line
			(start 1.2954 0.5842)
			(end 1.2954 -0.5842)
			(stroke
				(width 0.1524)
				(type default)
			)
			(layer "B.SilkS")
		)
		(fp_line
			(start 1.2954 -0.5842)
			(end -1.2954 -0.5842)
			(stroke
				(width 0.1524)
				(type default)
			)
			(layer "B.SilkS")
		)
		(fp_line
			(start -1.2954 0.5842)
			(end 1.2954 0.5842)
			(stroke
				(width 0.1524)
				(type default)
			)
			(layer "B.SilkS")
		)
		(fp_line
			(start -1.2954 -0.5842)
			(end -1.2954 0.5842)
			(stroke
				(width 0.1524)
				(type default)
			)
			(layer "B.SilkS")
		)
		(fp_line
			(start 1.1938 0.4064)
			(end 1.1938 -0.4064)
			(stroke
				(width 0.1)
				(type default)
			)
			(layer "B.Fab")
		)
		(fp_line
			(start 1.1938 -0.4064)
			(end 0.8636 -0.4064)
			(stroke
				(width 0.1)
				(type default)
			)
			(layer "B.Fab")
		)
		(fp_line
			(start 0.8636 0.4572)
			(end 0.8636 0.4064)
			(stroke
				(width 0.1)
				(type default)
			)
			(layer "B.Fab")
		)
		(fp_line
			(start 0.8636 0.4064)
			(end 1.1938 0.4064)
			(stroke
				(width 0.1)
				(type default)
			)
			(layer "B.Fab")
		)
		(fp_line
			(start 0.8636 -0.4064)
			(end 0.8636 -0.4572)
			(stroke
				(width 0.1)
				(type default)
			)
			(layer "B.Fab")
		)
		(fp_line
			(start 0.8636 -0.4572)
			(end -0.8636 -0.4572)
			(stroke
				(width 0.1)
				(type default)
			)
			(layer "B.Fab")
		)
		(fp_line
			(start -0.8636 0.4572)
			(end 0.8636 0.4572)
			(stroke
				(width 0.1)
				(type default)
			)
			(layer "B.Fab")
		)
		(fp_line
			(start -0.8636 0.4064)
			(end -0.8636 0.4572)
			(stroke
				(width 0.1)
				(type default)
			)
			(layer "B.Fab")
		)
		(fp_line
			(start -0.8636 -0.4064)
			(end -1.1938 -0.4064)
			(stroke
				(width 0.1)
				(type default)
			)
			(layer "B.Fab")
		)
		(fp_line
			(start -0.8636 -0.4572)
			(end -0.8636 -0.4064)
			(stroke
				(width 0.1)
				(type default)
			)
			(layer "B.Fab")
		)
		(fp_line
			(start -1.1938 0.4064)
			(end -0.8636 0.4064)
			(stroke
				(width 0.1)
				(type default)
			)
			(layer "B.Fab")
		)
		(fp_line
			(start -1.1938 -0.4064)
			(end -1.1938 0.4064)
			(stroke
				(width 0.1)
				(type default)
			)
			(layer "B.Fab")
		)
		(pad "1" smd rect
			(at 0.7366 0 90)
			(size 0.7112 0.8128)
			(layers "B.Cu" "B.Mask" "B.Paste")
			(net "FM_HS1_EN_FUSE")
		)
		(pad "2" smd rect
			(at -0.7366 0 90)
			(size 0.7112 0.8128)
			(layers "B.Cu" "B.Mask" "B.Paste")
			(net "GND")
		)
	)
	(footprint ""
		(layer "B.Cu")
		(at 285.9024 -71.882 180)
		(property "Reference" "R5869"
			(at 0 0 0)
			(layer "B.SilkS")
			(hide yes)
			(effects
				(font
					(size 1.27 1.27)
				)
				(justify mirror)
			)
		)
		(property "Value" ""
			(at 0 0 0)
			(layer "B.Fab")
			(effects
				(font
					(size 1.27 1.27)
				)
				(justify mirror)
			)
		)
		(duplicate_pad_numbers_are_jumpers no)
		(fp_line
			(start 0.7874 0.4064)
			(end 0.7874 -0.4064)
			(stroke
				(width 0.1524)
				(type default)
			)
			(layer "B.SilkS")
		)
		(fp_line
			(start 0.7874 -0.4064)
			(end -0.7874 -0.4064)
			(stroke
				(width 0.1524)
				(type default)
			)
			(layer "B.SilkS")
		)
		(fp_line
			(start -0.7874 0.4064)
			(end 0.7874 0.4064)
			(stroke
				(width 0.1524)
				(type default)
			)
			(layer "B.SilkS")
		)
		(fp_line
			(start -0.7874 -0.4064)
			(end -0.7874 0.4064)
			(stroke
				(width 0.1524)
				(type default)
			)
			(layer "B.SilkS")
		)
		(fp_line
			(start 0.67945 0.3048)
			(end 0.67945 -0.305054)
			(stroke
				(width 0.1)
				(type default)
			)
			(layer "B.Fab")
		)
		(fp_line
			(start 0.67945 -0.305054)
			(end 0.12065 -0.305054)
			(stroke
				(width 0.1)
				(type default)
			)
			(layer "B.Fab")
		)
		(fp_line
			(start 0.12065 0.3048)
			(end 0.67945 0.3048)
			(stroke
				(width 0.1)
				(type default)
			)
			(layer "B.Fab")
		)
		(fp_line
			(start 0.12065 0.2794)
			(end 0.12065 0.3048)
			(stroke
				(width 0.1)
				(type default)
			)
			(layer "B.Fab")
		)
		(fp_line
			(start 0.12065 -0.2794)
			(end -0.12065 -0.2794)
			(stroke
				(width 0.1)
				(type default)
			)
			(layer "B.Fab")
		)
		(fp_line
			(start 0.12065 -0.305054)
			(end 0.12065 -0.2794)
			(stroke
				(width 0.1)
				(type default)
			)
			(layer "B.Fab")
		)
		(fp_line
			(start -0.120396 0.3048)
			(end -0.120396 0.2794)
			(stroke
				(width 0.1)
				(type default)
			)
			(layer "B.Fab")
		)
		(fp_line
			(start -0.120396 0.2794)
			(end 0.12065 0.2794)
			(stroke
				(width 0.1)
				(type default)
			)
			(layer "B.Fab")
		)
		(fp_line
			(start -0.12065 -0.2794)
			(end -0.12065 -0.3048)
			(stroke
				(width 0.1)
				(type default)
			)
			(layer "B.Fab")
		)
		(fp_line
			(start -0.12065 -0.3048)
			(end -0.67945 -0.3048)
			(stroke
				(width 0.1)
				(type default)
			)
			(layer "B.Fab")
		)
		(fp_line
			(start -0.67945 0.3048)
			(end -0.120396 0.3048)
			(stroke
				(width 0.1)
				(type default)
			)
			(layer "B.Fab")
		)
		(fp_line
			(start -0.67945 -0.3048)
			(end -0.67945 0.3048)
			(stroke
				(width 0.1)
				(type default)
			)
			(layer "B.Fab")
		)
		(pad "1" smd circle
			(at 0.40005 0)
			(size 0 0)
			(layers "B.Cu" "B.Mask" "B.Paste")
			(net "SMB_P52V_PDB_SCL")
		)
		(pad "2" smd circle
			(at -0.40005 0)
			(size 0 0)
			(layers "B.Cu" "B.Mask" "B.Paste")
			(net "SMB_P52V_PDB_SCL_R3")
		)
	)
	(footprint ""
		(layer "B.Cu")
		(at 159.939736 -71.628 180)
		(property "Reference" "PR7006"
			(at 0 0 0)
			(layer "B.SilkS")
			(hide yes)
			(effects
				(font
					(size 1.27 1.27)
				)
				(justify mirror)
			)
		)
		(property "Value" ""
			(at 0 0 0)
			(layer "B.Fab")
			(effects
				(font
					(size 1.27 1.27)
				)
				(justify mirror)
			)
		)
		(duplicate_pad_numbers_are_jumpers no)
		(fp_line
			(start 0.7874 0.4064)
			(end 0.7874 -0.4064)
			(stroke
				(width 0.1524)
				(type default)
			)
			(layer "B.SilkS")
		)
		(fp_line
			(start 0.7874 -0.4064)
			(end -0.7874 -0.4064)
			(stroke
				(width 0.1524)
				(type default)
			)
			(layer "B.SilkS")
		)
		(fp_line
			(start -0.7874 0.4064)
			(end 0.7874 0.4064)
			(stroke
				(width 0.1524)
				(type default)
			)
			(layer "B.SilkS")
		)
		(fp_line
			(start -0.7874 -0.4064)
			(end -0.7874 0.4064)
			(stroke
				(width 0.1524)
				(type default)
			)
			(layer "B.SilkS")
		)
		(fp_line
			(start 0.67945 0.3048)
			(end 0.67945 -0.305054)
			(stroke
				(width 0.1)
				(type default)
			)
			(layer "B.Fab")
		)
		(fp_line
			(start 0.67945 -0.305054)
			(end 0.12065 -0.305054)
			(stroke
				(width 0.1)
				(type default)
			)
			(layer "B.Fab")
		)
		(fp_line
			(start 0.12065 0.3048)
			(end 0.67945 0.3048)
			(stroke
				(width 0.1)
				(type default)
			)
			(layer "B.Fab")
		)
		(fp_line
			(start 0.12065 0.2794)
			(end 0.12065 0.3048)
			(stroke
				(width 0.1)
				(type default)
			)
			(layer "B.Fab")
		)
		(fp_line
			(start 0.12065 -0.2794)
			(end -0.12065 -0.2794)
			(stroke
				(width 0.1)
				(type default)
			)
			(layer "B.Fab")
		)
		(fp_line
			(start 0.12065 -0.305054)
			(end 0.12065 -0.2794)
			(stroke
				(width 0.1)
				(type default)
			)
			(layer "B.Fab")
		)
		(fp_line
			(start -0.120396 0.3048)
			(end -0.120396 0.2794)
			(stroke
				(width 0.1)
				(type default)
			)
			(layer "B.Fab")
		)
		(fp_line
			(start -0.120396 0.2794)
			(end 0.12065 0.2794)
			(stroke
				(width 0.1)
				(type default)
			)
			(layer "B.Fab")
		)
		(fp_line
			(start -0.12065 -0.2794)
			(end -0.12065 -0.3048)
			(stroke
				(width 0.1)
				(type default)
			)
			(layer "B.Fab")
		)
		(fp_line
			(start -0.12065 -0.3048)
			(end -0.67945 -0.3048)
			(stroke
				(width 0.1)
				(type default)
			)
			(layer "B.Fab")
		)
		(fp_line
			(start -0.67945 0.3048)
			(end -0.120396 0.3048)
			(stroke
				(width 0.1)
				(type default)
			)
			(layer "B.Fab")
		)
		(fp_line
			(start -0.67945 -0.3048)
			(end -0.67945 0.3048)
			(stroke
				(width 0.1)
				(type default)
			)
			(layer "B.Fab")
		)
		(pad "1" smd circle
			(at 0.40005 0)
			(size 0 0)
			(layers "B.Cu" "B.Mask" "B.Paste")
			(net "P52V_HS2_SIO")
		)
		(pad "2" smd circle
			(at -0.40005 0)
			(size 0 0)
			(layers "B.Cu" "B.Mask" "B.Paste")
			(net "P52V_HS2_INTVCC")
		)
	)
	(footprint ""
		(layer "B.Cu")
		(at 278.7904 -73.533 180)
		(property "Reference" "PR6933"
			(at 0 0 0)
			(layer "B.SilkS")
			(hide yes)
			(effects
				(font
					(size 1.27 1.27)
				)
				(justify mirror)
			)
		)
		(property "Value" ""
			(at 0 0 0)
			(layer "B.Fab")
			(effects
				(font
					(size 1.27 1.27)
				)
				(justify mirror)
			)
		)
		(duplicate_pad_numbers_are_jumpers no)
		(fp_line
			(start 0.7874 0.4064)
			(end 0.7874 -0.4064)
			(stroke
				(width 0.1524)
				(type default)
			)
			(layer "B.SilkS")
		)
		(fp_line
			(start 0.7874 -0.4064)
			(end -0.7874 -0.4064)
			(stroke
				(width 0.1524)
				(type default)
			)
			(layer "B.SilkS")
		)
		(fp_line
			(start -0.7874 0.4064)
			(end 0.7874 0.4064)
			(stroke
				(width 0.1524)
				(type default)
			)
			(layer "B.SilkS")
		)
		(fp_line
			(start -0.7874 -0.4064)
			(end -0.7874 0.4064)
			(stroke
				(width 0.1524)
				(type default)
			)
			(layer "B.SilkS")
		)
		(fp_line
			(start 0.67945 0.3048)
			(end 0.67945 -0.305054)
			(stroke
				(width 0.1)
				(type default)
			)
			(layer "B.Fab")
		)
		(fp_line
			(start 0.67945 -0.305054)
			(end 0.12065 -0.305054)
			(stroke
				(width 0.1)
				(type default)
			)
			(layer "B.Fab")
		)
		(fp_line
			(start 0.12065 0.3048)
			(end 0.67945 0.3048)
			(stroke
				(width 0.1)
				(type default)
			)
			(layer "B.Fab")
		)
		(fp_line
			(start 0.12065 0.2794)
			(end 0.12065 0.3048)
			(stroke
				(width 0.1)
				(type default)
			)
			(layer "B.Fab")
		)
		(fp_line
			(start 0.12065 -0.2794)
			(end -0.12065 -0.2794)
			(stroke
				(width 0.1)
				(type default)
			)
			(layer "B.Fab")
		)
		(fp_line
			(start 0.12065 -0.305054)
			(end 0.12065 -0.2794)
			(stroke
				(width 0.1)
				(type default)
			)
			(layer "B.Fab")
		)
		(fp_line
			(start -0.120396 0.3048)
			(end -0.120396 0.2794)
			(stroke
				(width 0.1)
				(type default)
			)
			(layer "B.Fab")
		)
		(fp_line
			(start -0.120396 0.2794)
			(end 0.12065 0.2794)
			(stroke
				(width 0.1)
				(type default)
			)
			(layer "B.Fab")
		)
		(fp_line
			(start -0.12065 -0.2794)
			(end -0.12065 -0.3048)
			(stroke
				(width 0.1)
				(type default)
			)
			(layer "B.Fab")
		)
		(fp_line
			(start -0.12065 -0.3048)
			(end -0.67945 -0.3048)
			(stroke
				(width 0.1)
				(type default)
			)
			(layer "B.Fab")
		)
		(fp_line
			(start -0.67945 0.3048)
			(end -0.120396 0.3048)
			(stroke
				(width 0.1)
				(type default)
			)
			(layer "B.Fab")
		)
		(fp_line
			(start -0.67945 -0.3048)
			(end -0.67945 0.3048)
			(stroke
				(width 0.1)
				(type default)
			)
			(layer "B.Fab")
		)
		(pad "1" smd circle
			(at 0.40005 0)
			(size 0 0)
			(layers "B.Cu" "B.Mask" "B.Paste")
			(net "P52V_HS1_ISET")
		)
		(pad "2" smd circle
			(at -0.40005 0)
			(size 0 0)
			(layers "B.Cu" "B.Mask" "B.Paste")
			(net "P52V_HS1_VCAP")
		)
	)
)
